# S9S_MB_2U (Grand Teton) — schematic netlist excerpt (pin names and nets, part order shuffled) for the footprints in the layout excerpt that follows; sources: Cadence DE-HDL packaged netlist, KiCad conversion of 03242023_DA0F0TMBIJ0_F0T_Motherboard_J_brd_V01_OCP.brd

R3239  Q_RES  33.2 1% CHIP  pkg 0402LF  page 240 : A = SMB_OCP_SFF_3V3AUX_SDA ; B = SMB_OCP_SFF_3V3AUX_SDA_R0
R2257  Q_RES  0 5% EMPTY  pkg 0402LF  page 240 : A = USB2_7_R_DN ; B = USB2_7_DN

(kicad_pcb
	(version 20260206)
	(generator "pcbnew")
	(generator_version "10.0")
	(general
		(thickness 1.6)
		(legacy_teardrops no)
	)
	(paper "A4")
	(title_block
		(title "03242023_DA0F0TMBIJ0_F0T_Motherboard_J_brd_V01_OCP.brd")
		(comment 1 "Grand Teton / footprints 5418-5419 of 6105")
	)
	(layers
		(0 "F.Cu" signal "TOP")
		(4 "In1.Cu" signal "GND")
		(6 "In2.Cu" signal "IN1")
		(8 "In3.Cu" signal "GND1")
		(10 "In4.Cu" signal "IN2")
		(12 "In5.Cu" signal "GND2")
		(14 "In6.Cu" signal "IN3")
		(16 "In7.Cu" signal "GND3")
		(18 "In8.Cu" signal "VCC")
		(20 "In9.Cu" signal "VCC1")
		(22 "In10.Cu" signal "GND4")
		(24 "In11.Cu" signal "IN4")
		(26 "In12.Cu" signal "GND5")
		(28 "In13.Cu" signal "IN5")
		(30 "In14.Cu" signal "GND6")
		(32 "In15.Cu" signal "IN6")
		(34 "In16.Cu" signal "GND7")
		(2 "B.Cu" signal "BOTTOM")
		(9 "F.Adhes" user "F.Adhesive")
		(11 "B.Adhes" user "B.Adhesive")
		(13 "F.Paste" user "Package Geometry/Pastemask Top")
		(15 "B.Paste" user "Package Geometry/Pastemask Bottom")
		(5 "F.SilkS" user "Ref Des/Silkscreen Top")
		(7 "B.SilkS" user "Ref Des/Silkscreen Bottom")
		(1 "F.Mask" user "Board Geometry/Soldermask Top")
		(3 "B.Mask" user "Board Geometry/Soldermask Bottom")
		(17 "Dwgs.User" user "User.Drawings")
		(19 "Cmts.User" user "User.Comments")
		(21 "Eco1.User" user "User.Eco1")
		(23 "Eco2.User" user "User.Eco2")
		(25 "Edge.Cuts" user "Board Geometry/Outline")
		(27 "Margin" user)
		(31 "F.CrtYd" user "Package Geometry/Place Bound Top")
		(29 "B.CrtYd" user "Package Geometry/Place Bound Bottom")
		(35 "F.Fab" user "Ref Des/Assembly Top")
		(33 "B.Fab" user "Ref Des/Assembly Bottom")
	)
	(footprint ""
		(layer "B.Cu")
		(at 182.871618 -18.710148 90)
		(property "Reference" "R3239"
			(at 0 0 90)
			(layer "B.SilkS")
			(hide yes)
			(effects
				(font
					(size 1.27 1.27)
				)
				(justify mirror)
			)
		)
		(property "Value" ""
			(at 0 0 90)
			(layer "B.Fab")
			(effects
				(font
					(size 1.27 1.27)
				)
				(justify mirror)
			)
		)
		(duplicate_pad_numbers_are_jumpers no)
		(fp_line
			(start 0.7874 -0.4064)
			(end -0.7874 -0.4064)
			(stroke
				(width 0.1524)
				(type default)
			)
			(layer "B.SilkS")
		)
		(fp_line
			(start -0.7874 -0.4064)
			(end -0.7874 0.4064)
			(stroke
				(width 0.1524)
				(type default)
			)
			(layer "B.SilkS")
		)
		(fp_line
			(start 0.7874 0.4064)
			(end 0.7874 -0.4064)
			(stroke
				(width 0.1524)
				(type default)
			)
			(layer "B.SilkS")
		)
		(fp_line
			(start -0.7874 0.4064)
			(end 0.7874 0.4064)
			(stroke
				(width 0.1524)
				(type default)
			)
			(layer "B.SilkS")
		)
		(fp_line
			(start 0.67945 -0.305054)
			(end 0.12065 -0.305054)
			(stroke
				(width 0.1)
				(type default)
			)
			(layer "B.Fab")
		)
		(fp_line
			(start 0.12065 -0.305054)
			(end 0.12065 -0.2794)
			(stroke
				(width 0.1)
				(type default)
			)
			(layer "B.Fab")
		)
		(fp_line
			(start -0.12065 -0.3048)
			(end -0.67945 -0.3048)
			(stroke
				(width 0.1)
				(type default)
			)
			(layer "B.Fab")
		)
		(fp_line
			(start -0.67945 -0.3048)
			(end -0.67945 0.3048)
			(stroke
				(width 0.1)
				(type default)
			)
			(layer "B.Fab")
		)
		(fp_line
			(start 0.12065 -0.2794)
			(end -0.12065 -0.2794)
			(stroke
				(width 0.1)
				(type default)
			)
			(layer "B.Fab")
		)
		(fp_line
			(start -0.12065 -0.2794)
			(end -0.12065 -0.3048)
			(stroke
				(width 0.1)
				(type default)
			)
			(layer "B.Fab")
		)
		(fp_line
			(start 0.12065 0.2794)
			(end 0.12065 0.3048)
			(stroke
				(width 0.1)
				(type default)
			)
			(layer "B.Fab")
		)
		(fp_line
			(start -0.120396 0.2794)
			(end 0.12065 0.2794)
			(stroke
				(width 0.1)
				(type default)
			)
			(layer "B.Fab")
		)
		(fp_line
			(start 0.67945 0.3048)
			(end 0.67945 -0.305054)
			(stroke
				(width 0.1)
				(type default)
			)
			(layer "B.Fab")
		)
		(fp_line
			(start 0.12065 0.3048)
			(end 0.67945 0.3048)
			(stroke
				(width 0.1)
				(type default)
			)
			(layer "B.Fab")
		)
		(fp_line
			(start -0.120396 0.3048)
			(end -0.120396 0.2794)
			(stroke
				(width 0.1)
				(type default)
			)
			(layer "B.Fab")
		)
		(fp_line
			(start -0.67945 0.3048)
			(end -0.120396 0.3048)
			(stroke
				(width 0.1)
				(type default)
			)
			(layer "B.Fab")
		)
		(pad "1" smd circle
			(at 0.40005 0 270)
			(size 0 0)
			(layers "B.Cu" "B.Mask" "B.Paste")
			(net "SMB_OCP_SFF_3V3AUX_SDA")
		)
		(pad "2" smd circle
			(at -0.40005 0 270)
			(size 0 0)
			(layers "B.Cu" "B.Mask" "B.Paste")
			(net "SMB_OCP_SFF_3V3AUX_SDA_R0")
		)
	)
	(footprint ""
		(layer "B.Cu")
		(at 186.055254 -19.417792 -90)
		(property "Reference" "R2257"
			(at 0 0 90)
			(layer "B.SilkS")
			(hide yes)
			(effects
				(font
					(size 1.27 1.27)
				)
				(justify mirror)
			)
		)
		(property "Value" ""
			(at 0 0 90)
			(layer "B.Fab")
			(effects
				(font
					(size 1.27 1.27)
				)
				(justify mirror)
			)
		)
		(duplicate_pad_numbers_are_jumpers no)
		(fp_line
			(start -0.7874 0.4064)
			(end 0.7874 0.4064)
			(stroke
				(width 0.1524)
				(type default)
			)
			(layer "B.SilkS")
		)
		(fp_line
			(start 0.7874 0.4064)
			(end 0.7874 -0.154686)
			(stroke
				(width 0.1524)
				(type default)
			)
			(layer "B.SilkS")
		)
		(fp_line
			(start -0.7874 -0.131826)
			(end -0.7874 0.4064)
			(stroke
				(width 0.1524)
				(type default)
			)
			(layer "B.SilkS")
		)
		(fp_line
			(start 0.534924 -0.4064)
			(end -0.318516 -0.4064)
			(stroke
				(width 0.1524)
				(type default)
			)
			(layer "B.SilkS")
		)
		(fp_line
			(start -0.67945 0.3048)
			(end -0.120396 0.3048)
			(stroke
				(width 0.1)
				(type default)
			)
			(layer "B.Fab")
		)
		(fp_line
			(start -0.120396 0.3048)
			(end -0.120396 0.2794)
			(stroke
				(width 0.1)
				(type default)
			)
			(layer "B.Fab")
		)
		(fp_line
			(start 0.12065 0.3048)
			(end 0.67945 0.3048)
			(stroke
				(width 0.1)
				(type default)
			)
			(layer "B.Fab")
		)
		(fp_line
			(start 0.67945 0.3048)
			(end 0.67945 -0.305054)
			(stroke
				(width 0.1)
				(type default)
			)
			(layer "B.Fab")
		)
		(fp_line
			(start -0.120396 0.2794)
			(end 0.12065 0.2794)
			(stroke
				(width 0.1)
				(type default)
			)
			(layer "B.Fab")
		)
		(fp_line
			(start 0.12065 0.2794)
			(end 0.12065 0.3048)
			(stroke
				(width 0.1)
				(type default)
			)
			(layer "B.Fab")
		)
		(fp_line
			(start -0.12065 -0.2794)
			(end -0.12065 -0.3048)
			(stroke
				(width 0.1)
				(type default)
			)
			(layer "B.Fab")
		)
		(fp_line
			(start 0.12065 -0.2794)
			(end -0.12065 -0.2794)
			(stroke
				(width 0.1)
				(type default)
			)
			(layer "B.Fab")
		)
		(fp_line
			(start -0.67945 -0.3048)
			(end -0.67945 0.3048)
			(stroke
				(width 0.1)
				(type default)
			)
			(layer "B.Fab")
		)
		(fp_line
			(start -0.12065 -0.3048)
			(end -0.67945 -0.3048)
			(stroke
				(width 0.1)
				(type default)
			)
			(layer "B.Fab")
		)
		(fp_line
			(start 0.12065 -0.305054)
			(end 0.12065 -0.2794)
			(stroke
				(width 0.1)
				(type default)
			)
			(layer "B.Fab")
		)
		(fp_line
			(start 0.67945 -0.305054)
			(end 0.12065 -0.305054)
			(stroke
				(width 0.1)
				(type default)
			)
			(layer "B.Fab")
		)
		(pad "1" smd circle
			(at 0.40005 0 90)
			(size 0 0)
			(layers "B.Cu" "B.Mask" "B.Paste")
			(net "USB2_7_R_DN")
		)
		(pad "2" smd circle
			(at -0.40005 0 90)
			(size 0 0)
			(layers "B.Cu" "B.Mask" "B.Paste")
			(net "USB2_7_DN")
		)
	)
)
